# SCM (Grand Teton) — schematic netlist excerpt (pin names and nets, part order shuffled) for the footprints in the layout excerpt that follows; sources: Cadence DE-HDL packaged netlist, KiCad conversion of 12092022_DA0F0TMDCD0_F0T_Management_Board_D_brd_V3_OCP.brd

R264  Q_RES  2.2K 5% CHIP  pkg 0402LF  page 27 : A = P3V3_AUX ; B = SMB_BMC_MM16_SCL

Q6  2N7002A7  2N7002A-7 IC  pkg SOT23_GDSXC  page 29
  D  = FM_DEBUG_PORT_R_PRSNT_N
  G  = DEBUG_PORT_PRSNT
  S  = GND

(kicad_pcb
	(version 20260206)
	(generator "pcbnew")
	(generator_version "10.0")
	(general
		(thickness 1.6)
		(legacy_teardrops no)
	)
	(paper "A4")
	(title_block
		(title "12092022_DA0F0TMDCD0_F0T_Management_Board_D_brd_V3_OCP.brd")
		(comment 1 "Grand Teton / footprints 765-766 of 1440")
	)
	(layers
		(0 "F.Cu" signal "TOP")
		(4 "In1.Cu" signal "GND")
		(6 "In2.Cu" signal "IN1")
		(8 "In3.Cu" signal "GND1")
		(10 "In4.Cu" signal "IN2")
		(12 "In5.Cu" signal "VCC")
		(14 "In6.Cu" signal "VCC1")
		(16 "In7.Cu" signal "IN3")
		(18 "In8.Cu" signal "GND2")
		(20 "In9.Cu" signal "IN4")
		(22 "In10.Cu" signal "GND3")
		(2 "B.Cu" signal "BOTTOM")
		(9 "F.Adhes" user "F.Adhesive")
		(11 "B.Adhes" user "B.Adhesive")
		(13 "F.Paste" user "Package Geometry/Pastemask Top")
		(15 "B.Paste" user "Package Geometry/Pastemask Bottom")
		(5 "F.SilkS" user "Ref Des/Silkscreen Top")
		(7 "B.SilkS" user "Ref Des/Silkscreen Bottom")
		(1 "F.Mask" user "Board Geometry/Soldermask Top")
		(3 "B.Mask" user "Board Geometry/Soldermask Bottom")
		(17 "Dwgs.User" user "User.Drawings")
		(19 "Cmts.User" user "User.Comments")
		(21 "Eco1.User" user "User.Eco1")
		(23 "Eco2.User" user "User.Eco2")
		(25 "Edge.Cuts" user "Board Geometry/Outline")
		(27 "Margin" user)
		(31 "F.CrtYd" user "Package Geometry/Place Bound Top")
		(29 "B.CrtYd" user "Package Geometry/Place Bound Bottom")
		(35 "F.Fab" user "Ref Des/Assembly Top")
		(33 "B.Fab" user "Ref Des/Assembly Bottom")
	)
	(footprint ""
		(layer "B.Cu")
		(at 50.673 -30.861 -90)
		(property "Reference" "R264"
			(at 0 0 90)
			(layer "B.SilkS")
			(hide yes)
			(effects
				(font
					(size 1.27 1.27)
				)
				(justify mirror)
			)
		)
		(property "Value" ""
			(at 0 0 90)
			(layer "B.Fab")
			(effects
				(font
					(size 1.27 1.27)
				)
				(justify mirror)
			)
		)
		(duplicate_pad_numbers_are_jumpers no)
		(fp_line
			(start -0.7874 0.4064)
			(end 0.7874 0.4064)
			(stroke
				(width 0.1524)
				(type default)
			)
			(layer "B.SilkS")
		)
		(fp_line
			(start 0.7874 0.4064)
			(end 0.7874 -0.4064)
			(stroke
				(width 0.1524)
				(type default)
			)
			(layer "B.SilkS")
		)
		(fp_line
			(start -0.7874 -0.4064)
			(end -0.7874 0.4064)
			(stroke
				(width 0.1524)
				(type default)
			)
			(layer "B.SilkS")
		)
		(fp_line
			(start 0.7874 -0.4064)
			(end -0.7874 -0.4064)
			(stroke
				(width 0.1524)
				(type default)
			)
			(layer "B.SilkS")
		)
		(fp_line
			(start -0.67945 0.3048)
			(end -0.120396 0.3048)
			(stroke
				(width 0.1)
				(type default)
			)
			(layer "B.Fab")
		)
		(fp_line
			(start -0.120396 0.3048)
			(end -0.120396 0.2794)
			(stroke
				(width 0.1)
				(type default)
			)
			(layer "B.Fab")
		)
		(fp_line
			(start 0.12065 0.3048)
			(end 0.67945 0.3048)
			(stroke
				(width 0.1)
				(type default)
			)
			(layer "B.Fab")
		)
		(fp_line
			(start 0.67945 0.3048)
			(end 0.67945 -0.305054)
			(stroke
				(width 0.1)
				(type default)
			)
			(layer "B.Fab")
		)
		(fp_line
			(start -0.120396 0.2794)
			(end 0.12065 0.2794)
			(stroke
				(width 0.1)
				(type default)
			)
			(layer "B.Fab")
		)
		(fp_line
			(start 0.12065 0.2794)
			(end 0.12065 0.3048)
			(stroke
				(width 0.1)
				(type default)
			)
			(layer "B.Fab")
		)
		(fp_line
			(start -0.12065 -0.2794)
			(end -0.12065 -0.3048)
			(stroke
				(width 0.1)
				(type default)
			)
			(layer "B.Fab")
		)
		(fp_line
			(start 0.12065 -0.2794)
			(end -0.12065 -0.2794)
			(stroke
				(width 0.1)
				(type default)
			)
			(layer "B.Fab")
		)
		(fp_line
			(start -0.67945 -0.3048)
			(end -0.67945 0.3048)
			(stroke
				(width 0.1)
				(type default)
			)
			(layer "B.Fab")
		)
		(fp_line
			(start -0.12065 -0.3048)
			(end -0.67945 -0.3048)
			(stroke
				(width 0.1)
				(type default)
			)
			(layer "B.Fab")
		)
		(fp_line
			(start 0.12065 -0.305054)
			(end 0.12065 -0.2794)
			(stroke
				(width 0.1)
				(type default)
			)
			(layer "B.Fab")
		)
		(fp_line
			(start 0.67945 -0.305054)
			(end 0.12065 -0.305054)
			(stroke
				(width 0.1)
				(type default)
			)
			(layer "B.Fab")
		)
		(pad "1" smd circle
			(at 0.40005 0 90)
			(size 0 0)
			(layers "B.Cu" "B.Mask" "B.Paste")
			(net "P3V3_AUX")
		)
		(pad "2" smd circle
			(at -0.40005 0 90)
			(size 0 0)
			(layers "B.Cu" "B.Mask" "B.Paste")
			(net "SMB_BMC_MM16_SCL")
		)
	)
	(footprint ""
		(layer "B.Cu")
		(at 58.7375 -15.6337 -90)
		(property "Reference" "Q6"
			(at 2.52857 -1.4605 0)
			(unlocked yes)
			(layer "B.SilkS")
			(effects
				(font
					(size 0.7874 0.5842)
					(thickness 0.1524)
				)
				(justify left mirror)
			)
		)
		(property "Value" ""
			(at 0 0 90)
			(layer "B.Fab")
			(effects
				(font
					(size 1.27 1.27)
				)
				(justify mirror)
			)
		)
		(duplicate_pad_numbers_are_jumpers no)
		(fp_line
			(start -1.603248 1.500124)
			(end 1.603248 1.500124)
			(stroke
				(width 0.1524)
				(type default)
			)
			(layer "B.SilkS")
		)
		(fp_line
			(start 1.603248 1.500124)
			(end 1.603248 -1.500124)
			(stroke
				(width 0.1524)
				(type default)
			)
			(layer "B.SilkS")
		)
		(fp_line
			(start -1.603248 -1.500124)
			(end -1.603248 1.500124)
			(stroke
				(width 0.1524)
				(type default)
			)
			(layer "B.SilkS")
		)
		(fp_line
			(start 1.603248 -1.500124)
			(end -1.603248 -1.500124)
			(stroke
				(width 0.1524)
				(type default)
			)
			(layer "B.SilkS")
		)
		(fp_line
			(start -0.700024 1.500124)
			(end -0.700024 0.219964)
			(stroke
				(width 0.1)
				(type default)
			)
			(layer "B.Fab")
		)
		(fp_line
			(start 0.700024 1.500124)
			(end -0.700024 1.500124)
			(stroke
				(width 0.1)
				(type default)
			)
			(layer "B.Fab")
		)
		(fp_line
			(start 0.700024 1.169924)
			(end 0.700024 1.500124)
			(stroke
				(width 0.1)
				(type default)
			)
			(layer "B.Fab")
		)
		(fp_line
			(start 1.249934 1.169924)
			(end 0.700024 1.169924)
			(stroke
				(width 0.1)
				(type default)
			)
			(layer "B.Fab")
		)
		(fp_line
			(start 0.6985 0.729996)
			(end 1.249934 0.729996)
			(stroke
				(width 0.1)
				(type default)
			)
			(layer "B.Fab")
		)
		(fp_line
			(start 1.249934 0.729996)
			(end 1.249934 1.169924)
			(stroke
				(width 0.1)
				(type default)
			)
			(layer "B.Fab")
		)
		(fp_line
			(start -1.249934 0.219964)
			(end -1.249934 -0.219964)
			(stroke
				(width 0.1)
				(type default)
			)
			(layer "B.Fab")
		)
		(fp_line
			(start -0.700024 0.219964)
			(end -1.249934 0.219964)
			(stroke
				(width 0.1)
				(type default)
			)
			(layer "B.Fab")
		)
		(fp_line
			(start -1.249934 -0.219964)
			(end -0.700024 -0.219964)
			(stroke
				(width 0.1)
				(type default)
			)
			(layer "B.Fab")
		)
		(fp_line
			(start -0.700024 -0.219964)
			(end -0.700024 -1.500124)
			(stroke
				(width 0.1)
				(type default)
			)
			(layer "B.Fab")
		)
		(fp_line
			(start 0.6985 -0.729996)
			(end 0.6985 0.729996)
			(stroke
				(width 0.1)
				(type default)
			)
			(layer "B.Fab")
		)
		(fp_line
			(start 1.249934 -0.729996)
			(end 0.6985 -0.729996)
			(stroke
				(width 0.1)
				(type default)
			)
			(layer "B.Fab")
		)
		(fp_line
			(start 0.700024 -1.169924)
			(end 1.249934 -1.169924)
			(stroke
				(width 0.1)
				(type default)
			)
			(layer "B.Fab")
		)
		(fp_line
			(start 1.249934 -1.169924)
			(end 1.249934 -0.729996)
			(stroke
				(width 0.1)
				(type default)
			)
			(layer "B.Fab")
		)
		(fp_line
			(start -0.700024 -1.500124)
			(end 0.700024 -1.500124)
			(stroke
				(width 0.1)
				(type default)
			)
			(layer "B.Fab")
		)
		(fp_line
			(start 0.700024 -1.500124)
			(end 0.700024 -1.169924)
			(stroke
				(width 0.1)
				(type default)
			)
			(layer "B.Fab")
		)
		(fp_rect
			(start 0.700024 1.500124)
			(end -0.700024 -1.500124)
			(stroke
				(width 0)
				(type default)
			)
			(fill no)
			(layer "B.Fab")
		)
		(pad "D" smd rect
			(at -0.999998 0 180)
			(size 0.8128 0.9144)
			(layers "B.Cu" "B.Mask" "B.Paste")
			(net "FM_DEBUG_PORT_R_PRSNT_N")
		)
		(pad "G" smd rect
			(at 0.999998 -0.94996 180)
			(size 0.8128 0.9144)
			(layers "B.Cu" "B.Mask" "B.Paste")
			(net "DEBUG_PORT_PRSNT")
		)
		(pad "S" smd rect
			(at 0.999998 0.94996 180)
			(size 0.8128 0.9144)
			(layers "B.Cu" "B.Mask" "B.Paste")
			(net "GND")
		)
	)
)
